(kicad_pcb
	(version 20260206)
	(generator "pcbnew")
	(generator_version "10.0")
	(general
		(thickness 1.6)
		(legacy_teardrops no)
	)
	(paper "A4")
	(title_block
		(title "03242023_DA0F0TMBIJ0_F0T_Motherboard_J_brd_V01_OCP.brd")
		(comment 1 "Grand Teton / footprints 2047-2047 of 6105")
	)
	(layers
		(0 "F.Cu" signal "TOP")
		(4 "In1.Cu" signal "GND")
		(6 "In2.Cu" signal "IN1")
		(8 "In3.Cu" signal "GND1")
		(10 "In4.Cu" signal "IN2")
		(12 "In5.Cu" signal "GND2")
		(14 "In6.Cu" signal "IN3")
		(16 "In7.Cu" signal "GND3")
		(18 "In8.Cu" signal "VCC")
		(20 "In9.Cu" signal "VCC1")
		(22 "In10.Cu" signal "GND4")
		(24 "In11.Cu" signal "IN4")
		(26 "In12.Cu" signal "GND5")
		(28 "In13.Cu" signal "IN5")
		(30 "In14.Cu" signal "GND6")
		(32 "In15.Cu" signal "IN6")
		(34 "In16.Cu" signal "GND7")
		(2 "B.Cu" signal "BOTTOM")
		(9 "F.Adhes" user "F.Adhesive")
		(11 "B.Adhes" user "B.Adhesive")
		(13 "F.Paste" user "Package Geometry/Pastemask Top")
		(15 "B.Paste" user "Package Geometry/Pastemask Bottom")
		(5 "F.SilkS" user "Ref Des/Silkscreen Top")
		(7 "B.SilkS" user "Ref Des/Silkscreen Bottom")
		(1 "F.Mask" user "Board Geometry/Soldermask Top")
		(3 "B.Mask" user "Board Geometry/Soldermask Bottom")
		(17 "Dwgs.User" user "User.Drawings")
		(19 "Cmts.User" user "User.Comments")
		(21 "Eco1.User" user "User.Eco1")
		(23 "Eco2.User" user "User.Eco2")
		(25 "Edge.Cuts" user "Board Geometry/Outline")
		(27 "Margin" user)
		(31 "F.CrtYd" user "Package Geometry/Place Bound Top")
		(29 "B.CrtYd" user "Package Geometry/Place Bound Bottom")
		(35 "F.Fab" user "Ref Des/Assembly Top")
		(33 "B.Fab" user "Ref Des/Assembly Bottom")
	)
	(footprint ""
		(layer "F.Cu")
		(at 314.03544 -62.060328 180)
		(property "Reference" "R4564"
			(at 0 0 180)
			(layer "F.SilkS")
			(hide yes)
			(effects
				(font
					(size 1.27 1.27)
				)
			)
		)
		(property "Value" ""
			(at 0 0 180)
			(layer "F.Fab")
			(effects
				(font
					(size 1.27 1.27)
				)
			)
		)
		(duplicate_pad_numbers_are_jumpers no)
		(fp_line
			(start 0.7874 0.4064)
			(end -0.7874 0.4064)
			(stroke
				(width 0.1524)
				(type default)
			)
			(layer "F.SilkS")
		)
		(fp_line
			(start 0.7874 -0.4064)
			(end 0.7874 0.4064)
			(stroke
				(width 0.1524)
				(type default)
			)
			(layer "F.SilkS")
		)
		(fp_line
			(start -0.7874 0.4064)
			(end -0.7874 -0.4064)
			(stroke
				(width 0.1524)
				(type default)
			)
			(layer "F.SilkS")
		)
		(fp_line
			(start -0.7874 -0.4064)
			(end 0.7874 -0.4064)
			(stroke
				(width 0.1524)
				(type default)
			)
			(layer "F.SilkS")
		)
		(fp_line
			(start 0.67945 0.3048)
			(end 0.120396 0.3048)
			(stroke
				(width 0.1)
				(type default)
			)
			(layer "F.Fab")
		)
		(fp_line
			(start 0.67945 -0.3048)
			(end 0.67945 0.3048)
			(stroke
				(width 0.1)
				(type default)
			)
			(layer "F.Fab")
		)
		(fp_line
			(start 0.12065 -0.2794)
			(end 0.12065 -0.3048)
			(stroke
				(width 0.1)
				(type default)
			)
			(layer "F.Fab")
		)
		(fp_line
			(start 0.12065 -0.3048)
			(end 0.67945 -0.3048)
			(stroke
				(width 0.1)
				(type default)
			)
			(layer "F.Fab")
		)
		(fp_line
			(start 0.120396 0.3048)
			(end 0.120396 0.2794)
			(stroke
				(width 0.1)
				(type default)
			)
			(layer "F.Fab")
		)
		(fp_line
			(start 0.120396 0.2794)
			(end -0.12065 0.2794)
			(stroke
				(width 0.1)
				(type default)
			)
			(layer "F.Fab")
		)
		(fp_line
			(start -0.12065 0.3048)
			(end -0.67945 0.3048)
			(stroke
				(width 0.1)
				(type default)
			)
			(layer "F.Fab")
		)
		(fp_line
			(start -0.12065 0.2794)
			(end -0.12065 0.3048)
			(stroke
				(width 0.1)
				(type default)
			)
			(layer "F.Fab")
		)
		(fp_line
			(start -0.12065 -0.2794)
			(end 0.12065 -0.2794)
			(stroke
				(width 0.1)
				(type default)
			)
			(layer "F.Fab")
		)
		(fp_line
			(start -0.12065 -0.305054)
			(end -0.12065 -0.2794)
			(stroke
				(width 0.1)
				(type default)
			)
			(layer "F.Fab")
		)
		(fp_line
			(start -0.67945 0.3048)
			(end -0.67945 -0.305054)
			(stroke
				(width 0.1)
				(type default)
			)
			(layer "F.Fab")
		)
		(fp_line
			(start -0.67945 -0.305054)
			(end -0.12065 -0.305054)
			(stroke
				(width 0.1)
				(type default)
			)
			(layer "F.Fab")
		)
		(pad "1" smd circle
			(at -0.40005 0 180)
			(size 0 0)
			(layers "F.Cu" "F.Mask" "F.Paste")
			(net "PD_GPP_I_14")
		)
		(pad "2" smd circle
			(at 0.40005 0 180)
			(size 0 0)
			(layers "F.Cu" "F.Mask" "F.Paste")
			(net "GND")
		)
	)
)
